(kicad_pcb
	(version 20260206)
	(generator "pcbnew")
	(generator_version "10.0")
	(general
		(thickness 1.6)
		(legacy_teardrops no)
	)
	(paper "A4")
	(title_block
		(title "Bryce Canyon_SCC_16316-1_OCP.brd")
		(comment 1 "Bryce Canyon / footprint 64 of 1561 (U1), pads 239-349 of 1020")
	)
	(layers
		(0 "F.Cu" signal "TOP")
		(4 "In1.Cu" signal "L2GND")
		(6 "In2.Cu" signal "L3")
		(8 "In3.Cu" signal "L4VCC")
		(10 "In4.Cu" signal "L5VCC")
		(12 "In5.Cu" signal "L6")
		(14 "In6.Cu" signal "L7GND")
		(2 "B.Cu" signal "BOTTOM")
		(9 "F.Adhes" user "F.Adhesive")
		(11 "B.Adhes" user "B.Adhesive")
		(13 "F.Paste" user "Package Geometry/Pastemask Top")
		(15 "B.Paste" user "Package Geometry/Pastemask Bottom")
		(5 "F.SilkS" user "Ref Des/Silkscreen Top")
		(7 "B.SilkS" user "Ref Des/Silkscreen Bottom")
		(1 "F.Mask" user "Board Geometry/Soldermask Top")
		(3 "B.Mask" user "Board Geometry/Soldermask Bottom")
		(17 "Dwgs.User" user "User.Drawings")
		(19 "Cmts.User" user "User.Comments")
		(21 "Eco1.User" user "User.Eco1")
		(23 "Eco2.User" user "User.Eco2")
		(25 "Edge.Cuts" user "Board Geometry/Outline")
		(27 "Margin" user)
		(31 "F.CrtYd" user "Package Geometry/Place Bound Top")
		(29 "B.CrtYd" user "Package Geometry/Place Bound Bottom")
		(35 "F.Fab" user "Ref Des/Assembly Top")
		(33 "B.Fab" user "Ref Des/Assembly Bottom")
	)
	(footprint ""
		(layer "F.Cu")
		(at 115.000024 -67.00012)
		(property "Reference" "U1"
			(at 0 0 0)
			(layer "F.SilkS")
			(hide yes)
			(effects
				(font
					(size 1.27 1.27)
				)
			)
		)
		(property "Value" "LSISAS3X48-GP"
			(at -24.358092 -5.0292 0)
			(unlocked yes)
			(layer "F.Fab")
			(hide yes)
			(effects
				(font
					(size 1.016 1.016)
					(thickness 0.1524)
				)
			)
		)
		(property "Device Type" "BGA1020C33H83"
			(at -24.358092 -6.5532 0)
			(unlocked yes)
			(layer "F.Fab")
			(hide yes)
			(effects
				(font
					(size 1.016 1.016)
					(thickness 0.1524)
				)
			)
		)
		(duplicate_pad_numbers_are_jumpers no)
		(pad "AG17" smd circle
			(at 0.500126 10.500106)
			(size 0.4572 0.4572)
			(layers "F.Cu" "F.Mask" "F.Paste")
			(net "PHY_DPB_TO_SCC_C_27_DN")
		)
		(pad "AG18" smd circle
			(at 1.500124 10.500106)
			(size 0.4572 0.4572)
			(layers "F.Cu" "F.Mask" "F.Paste")
			(net "PHY_DPB_TO_SCC_C_32_DN")
		)
		(pad "AG19" smd circle
			(at 2.500122 10.500106)
			(size 0.4572 0.4572)
			(layers "F.Cu" "F.Mask" "F.Paste")
			(net "PHY_DPB_TO_SCC_C_33_DN")
		)
		(pad "AG20" smd circle
			(at 3.50012 10.500106)
			(size 0.4572 0.4572)
			(layers "F.Cu" "F.Mask" "F.Paste")
			(net "PHY_DPB_TO_SCC_C_34_DN")
		)
		(pad "AG21" smd circle
			(at 4.500118 10.500106)
			(size 0.4572 0.4572)
			(layers "F.Cu" "F.Mask" "F.Paste")
			(net "PHY_DPB_TO_SCC_C_35_DN")
		)
		(pad "AG22" smd circle
			(at 5.500116 10.500106)
			(size 0.4572 0.4572)
			(layers "F.Cu" "F.Mask" "F.Paste")
			(net "PHY_DPB_TO_SCC_C_36_DN")
		)
		(pad "AG23" smd circle
			(at 6.500114 10.500106)
			(size 0.4572 0.4572)
			(layers "F.Cu" "F.Mask" "F.Paste")
			(net "PHY_DPB_TO_SCC_C_37_DN")
		)
		(pad "AG24" smd circle
			(at 7.500112 10.500106)
			(size 0.4572 0.4572)
			(layers "F.Cu" "F.Mask" "F.Paste")
			(net "PHY_DPB_TO_SCC_C_38_DN")
		)
		(pad "AG25" smd circle
			(at 8.50011 10.500106)
			(size 0.4572 0.4572)
			(layers "F.Cu" "F.Mask" "F.Paste")
			(net "PHY_DPB_TO_SCC_C_39_DN")
		)
		(pad "AG26" smd circle
			(at 9.500108 10.500106)
			(size 0.4572 0.4572)
			(layers "F.Cu" "F.Mask" "F.Paste")
			(net "GND")
		)
		(pad "AG27" smd circle
			(at 10.500106 10.500106)
			(size 0.4572 0.4572)
			(layers "F.Cu" "F.Mask" "F.Paste")
			(net "PHY_IOC_TO_SCC_C_43_DN")
		)
		(pad "AG28" smd circle
			(at 11.500104 10.500106)
			(size 0.4572 0.4572)
			(layers "F.Cu" "F.Mask" "F.Paste")
			(net "PHY_IOC_TO_SCC_C_43_DP")
		)
		(pad "AG29" smd circle
			(at 12.500102 10.500106)
			(size 0.4572 0.4572)
			(layers "F.Cu" "F.Mask" "F.Paste")
			(net "GND")
		)
		(pad "AG30" smd circle
			(at 13.5001 10.500106)
			(size 0.4572 0.4572)
			(layers "F.Cu" "F.Mask" "F.Paste")
			(net "GB_VDDA")
		)
		(pad "AG31" smd circle
			(at 14.500098 10.500106)
			(size 0.4572 0.4572)
			(layers "F.Cu" "F.Mask" "F.Paste")
			(net "PHY_SCC_TO_IOC_43_DN")
		)
		(pad "AG32" smd circle
			(at 15.500096 10.500106)
			(size 0.4572 0.4572)
			(layers "F.Cu" "F.Mask" "F.Paste")
			(net "PHY_SCC_TO_IOC_43_DP")
		)
		(pad "AH1" smd circle
			(at -15.500096 11.500104)
			(size 0.4572 0.4572)
			(layers "F.Cu" "F.Mask" "F.Paste")
			(net "PHY_DPB_TO_SCC_C_12_DN")
		)
		(pad "AH2" smd circle
			(at -14.500098 11.500104)
			(size 0.4572 0.4572)
			(layers "F.Cu" "F.Mask" "F.Paste")
			(net "GND")
		)
		(pad "AH3" smd circle
			(at -13.5001 11.500104)
			(size 0.4572 0.4572)
			(layers "F.Cu" "F.Mask" "F.Paste")
			(net "PHY_DPB_TO_SCC_C_13_DP")
		)
		(pad "AH4" smd circle
			(at -12.500102 11.500104)
			(size 0.4572 0.4572)
			(layers "F.Cu" "F.Mask" "F.Paste")
			(net "PHY_DPB_TO_SCC_C_14_DP")
		)
		(pad "AH5" smd circle
			(at -11.500104 11.500104)
			(size 0.4572 0.4572)
			(layers "F.Cu" "F.Mask" "F.Paste")
			(net "PHY_DPB_TO_SCC_C_15_DP")
		)
		(pad "AH6" smd circle
			(at -10.500106 11.500104)
			(size 0.4572 0.4572)
			(layers "F.Cu" "F.Mask" "F.Paste")
			(net "PHY_DPB_TO_SCC_C_16_DP")
		)
		(pad "AH7" smd circle
			(at -9.500108 11.500104)
			(size 0.4572 0.4572)
			(layers "F.Cu" "F.Mask" "F.Paste")
			(net "PHY_DPB_TO_SCC_C_17_DP")
		)
		(pad "AH8" smd circle
			(at -8.50011 11.500104)
			(size 0.4572 0.4572)
			(layers "F.Cu" "F.Mask" "F.Paste")
			(net "PHY_DPB_TO_SCC_C_18_DP")
		)
		(pad "AH9" smd circle
			(at -7.500112 11.500104)
			(size 0.4572 0.4572)
			(layers "F.Cu" "F.Mask" "F.Paste")
			(net "PHY_DPB_TO_SCC_C_19_DP")
		)
		(pad "AH10" smd circle
			(at -6.500114 11.500104)
			(size 0.4572 0.4572)
			(layers "F.Cu" "F.Mask" "F.Paste")
			(net "PHY_DPB_TO_SCC_C_20_DP")
		)
		(pad "AH11" smd circle
			(at -5.500116 11.500104)
			(size 0.4572 0.4572)
			(layers "F.Cu" "F.Mask" "F.Paste")
			(net "PHY_DPB_TO_SCC_C_21_DP")
		)
		(pad "AH12" smd circle
			(at -4.500118 11.500104)
			(size 0.4572 0.4572)
			(layers "F.Cu" "F.Mask" "F.Paste")
			(net "PHY_DPB_TO_SCC_C_22_DP")
		)
		(pad "AH13" smd circle
			(at -3.50012 11.500104)
			(size 0.4572 0.4572)
			(layers "F.Cu" "F.Mask" "F.Paste")
			(net "PHY_DPB_TO_SCC_C_23_DP")
		)
		(pad "AH14" smd circle
			(at -2.500122 11.500104)
			(size 0.4572 0.4572)
			(layers "F.Cu" "F.Mask" "F.Paste")
			(net "PHY_DPB_TO_SCC_C_24_DP")
		)
		(pad "AH15" smd circle
			(at -1.500124 11.500104)
			(size 0.4572 0.4572)
			(layers "F.Cu" "F.Mask" "F.Paste")
			(net "PHY_DPB_TO_SCC_C_25_DP")
		)
		(pad "AH16" smd circle
			(at -0.500126 11.500104)
			(size 0.4572 0.4572)
			(layers "F.Cu" "F.Mask" "F.Paste")
			(net "PHY_DPB_TO_SCC_C_26_DP")
		)
		(pad "AH17" smd circle
			(at 0.500126 11.500104)
			(size 0.4572 0.4572)
			(layers "F.Cu" "F.Mask" "F.Paste")
			(net "PHY_DPB_TO_SCC_C_27_DP")
		)
		(pad "AH18" smd circle
			(at 1.500124 11.500104)
			(size 0.4572 0.4572)
			(layers "F.Cu" "F.Mask" "F.Paste")
			(net "PHY_DPB_TO_SCC_C_32_DP")
		)
		(pad "AH19" smd circle
			(at 2.500122 11.500104)
			(size 0.4572 0.4572)
			(layers "F.Cu" "F.Mask" "F.Paste")
			(net "PHY_DPB_TO_SCC_C_33_DP")
		)
		(pad "AH20" smd circle
			(at 3.50012 11.500104)
			(size 0.4572 0.4572)
			(layers "F.Cu" "F.Mask" "F.Paste")
			(net "PHY_DPB_TO_SCC_C_34_DP")
		)
		(pad "AH21" smd circle
			(at 4.500118 11.500104)
			(size 0.4572 0.4572)
			(layers "F.Cu" "F.Mask" "F.Paste")
			(net "PHY_DPB_TO_SCC_C_35_DP")
		)
		(pad "AH22" smd circle
			(at 5.500116 11.500104)
			(size 0.4572 0.4572)
			(layers "F.Cu" "F.Mask" "F.Paste")
			(net "PHY_DPB_TO_SCC_C_36_DP")
		)
		(pad "AH23" smd circle
			(at 6.500114 11.500104)
			(size 0.4572 0.4572)
			(layers "F.Cu" "F.Mask" "F.Paste")
			(net "PHY_DPB_TO_SCC_C_37_DP")
		)
		(pad "AH24" smd circle
			(at 7.500112 11.500104)
			(size 0.4572 0.4572)
			(layers "F.Cu" "F.Mask" "F.Paste")
			(net "PHY_DPB_TO_SCC_C_38_DP")
		)
		(pad "AH25" smd circle
			(at 8.50011 11.500104)
			(size 0.4572 0.4572)
			(layers "F.Cu" "F.Mask" "F.Paste")
			(net "PHY_DPB_TO_SCC_C_39_DP")
		)
		(pad "AH26" smd circle
			(at 9.500108 11.500104)
			(size 0.4572 0.4572)
			(layers "F.Cu" "F.Mask" "F.Paste")
			(net "GND")
		)
		(pad "AH27" smd circle
			(at 10.500106 11.500104)
			(size 0.4572 0.4572)
			(layers "F.Cu" "F.Mask" "F.Paste")
			(net "PHY_IOC_TO_SCC_C_42_DN")
		)
		(pad "AH28" smd circle
			(at 11.500104 11.500104)
			(size 0.4572 0.4572)
			(layers "F.Cu" "F.Mask" "F.Paste")
			(net "PHY_IOC_TO_SCC_C_42_DP")
		)
		(pad "AH29" smd circle
			(at 12.500102 11.500104)
			(size 0.4572 0.4572)
			(layers "F.Cu" "F.Mask" "F.Paste")
			(net "GB_VDDA")
		)
		(pad "AH30" smd circle
			(at 13.5001 11.500104)
			(size 0.4572 0.4572)
			(layers "F.Cu" "F.Mask" "F.Paste")
			(net "PHY_SCC_TO_IOC_42_DN")
		)
		(pad "AH31" smd circle
			(at 14.500098 11.500104)
			(size 0.4572 0.4572)
			(layers "F.Cu" "F.Mask" "F.Paste")
			(net "PHY_SCC_TO_IOC_42_DP")
		)
		(pad "AH32" smd circle
			(at 15.500096 11.500104)
			(size 0.4572 0.4572)
			(layers "F.Cu" "F.Mask" "F.Paste")
			(net "GND")
		)
		(pad "AJ1" smd circle
			(at -15.500096 12.500102)
			(size 0.4572 0.4572)
			(layers "F.Cu" "F.Mask" "F.Paste")
			(net "PHY_DPB_TO_SCC_C_12_DP")
		)
		(pad "AJ2" smd circle
			(at -14.500098 12.500102)
			(size 0.4572 0.4572)
			(layers "F.Cu" "F.Mask" "F.Paste")
			(net "GND")
		)
		(pad "AJ3" smd circle
			(at -13.5001 12.500102)
			(size 0.4572 0.4572)
			(layers "F.Cu" "F.Mask" "F.Paste")
			(net "GND")
		)
		(pad "AJ4" smd circle
			(at -12.500102 12.500102)
			(size 0.4572 0.4572)
			(layers "F.Cu" "F.Mask" "F.Paste")
			(net "GND")
		)
		(pad "AJ5" smd circle
			(at -11.500104 12.500102)
			(size 0.4572 0.4572)
			(layers "F.Cu" "F.Mask" "F.Paste")
			(net "GB_VDDA")
		)
		(pad "AJ6" smd circle
			(at -10.500106 12.500102)
			(size 0.4572 0.4572)
			(layers "F.Cu" "F.Mask" "F.Paste")
			(net "GND")
		)
		(pad "AJ7" smd circle
			(at -9.500108 12.500102)
			(size 0.4572 0.4572)
			(layers "F.Cu" "F.Mask" "F.Paste")
			(net "GB_VDDA")
		)
		(pad "AJ8" smd circle
			(at -8.50011 12.500102)
			(size 0.4572 0.4572)
			(layers "F.Cu" "F.Mask" "F.Paste")
			(net "GND")
		)
		(pad "AJ9" smd circle
			(at -7.500112 12.500102)
			(size 0.4572 0.4572)
			(layers "F.Cu" "F.Mask" "F.Paste")
			(net "GB_VDDA")
		)
		(pad "AJ10" smd circle
			(at -6.500114 12.500102)
			(size 0.4572 0.4572)
			(layers "F.Cu" "F.Mask" "F.Paste")
			(net "GND")
		)
		(pad "AJ11" smd circle
			(at -5.500116 12.500102)
			(size 0.4572 0.4572)
			(layers "F.Cu" "F.Mask" "F.Paste")
			(net "GB_VDDA")
		)
		(pad "AJ12" smd circle
			(at -4.500118 12.500102)
			(size 0.4572 0.4572)
			(layers "F.Cu" "F.Mask" "F.Paste")
			(net "GND")
		)
		(pad "AJ13" smd circle
			(at -3.50012 12.500102)
			(size 0.4572 0.4572)
			(layers "F.Cu" "F.Mask" "F.Paste")
			(net "GB_VDDA")
		)
		(pad "AJ14" smd circle
			(at -2.500122 12.500102)
			(size 0.4572 0.4572)
			(layers "F.Cu" "F.Mask" "F.Paste")
			(net "GND")
		)
		(pad "AJ15" smd circle
			(at -1.500124 12.500102)
			(size 0.4572 0.4572)
			(layers "F.Cu" "F.Mask" "F.Paste")
			(net "GB_VDDA")
		)
		(pad "AJ16" smd circle
			(at -0.500126 12.500102)
			(size 0.4572 0.4572)
			(layers "F.Cu" "F.Mask" "F.Paste")
			(net "GND")
		)
		(pad "AJ17" smd circle
			(at 0.500126 12.500102)
			(size 0.4572 0.4572)
			(layers "F.Cu" "F.Mask" "F.Paste")
			(net "GB_VDDA")
		)
		(pad "AJ18" smd circle
			(at 1.500124 12.500102)
			(size 0.4572 0.4572)
			(layers "F.Cu" "F.Mask" "F.Paste")
			(net "GND")
		)
		(pad "AJ19" smd circle
			(at 2.500122 12.500102)
			(size 0.4572 0.4572)
			(layers "F.Cu" "F.Mask" "F.Paste")
			(net "GB_VDDA")
		)
		(pad "AJ20" smd circle
			(at 3.50012 12.500102)
			(size 0.4572 0.4572)
			(layers "F.Cu" "F.Mask" "F.Paste")
			(net "GND")
		)
		(pad "AJ21" smd circle
			(at 4.500118 12.500102)
			(size 0.4572 0.4572)
			(layers "F.Cu" "F.Mask" "F.Paste")
			(net "GB_VDDA")
		)
		(pad "AJ22" smd circle
			(at 5.500116 12.500102)
			(size 0.4572 0.4572)
			(layers "F.Cu" "F.Mask" "F.Paste")
			(net "GND")
		)
		(pad "AJ23" smd circle
			(at 6.500114 12.500102)
			(size 0.4572 0.4572)
			(layers "F.Cu" "F.Mask" "F.Paste")
			(net "GB_VDDA")
		)
		(pad "AJ24" smd circle
			(at 7.500112 12.500102)
			(size 0.4572 0.4572)
			(layers "F.Cu" "F.Mask" "F.Paste")
			(net "GND")
		)
		(pad "AJ25" smd circle
			(at 8.50011 12.500102)
			(size 0.4572 0.4572)
			(layers "F.Cu" "F.Mask" "F.Paste")
			(net "GB_VDDA")
		)
		(pad "AJ26" smd circle
			(at 9.500108 12.500102)
			(size 0.4572 0.4572)
			(layers "F.Cu" "F.Mask" "F.Paste")
			(net "GND")
		)
		(pad "AJ27" smd circle
			(at 10.500106 12.500102)
			(size 0.4572 0.4572)
			(layers "F.Cu" "F.Mask" "F.Paste")
			(net "PHY_IOC_TO_SCC_C_41_DN")
		)
		(pad "AJ28" smd circle
			(at 11.500104 12.500102)
			(size 0.4572 0.4572)
			(layers "F.Cu" "F.Mask" "F.Paste")
			(net "PHY_IOC_TO_SCC_C_41_DP")
		)
		(pad "AJ29" smd circle
			(at 12.500102 12.500102)
			(size 0.4572 0.4572)
			(layers "F.Cu" "F.Mask" "F.Paste")
			(net "GND")
		)
		(pad "AJ30" smd circle
			(at 13.5001 12.500102)
			(size 0.4572 0.4572)
			(layers "F.Cu" "F.Mask" "F.Paste")
			(net "GB_VDDA")
		)
		(pad "AJ31" smd circle
			(at 14.500098 12.500102)
			(size 0.4572 0.4572)
			(layers "F.Cu" "F.Mask" "F.Paste")
			(net "PHY_SCC_TO_IOC_41_DN")
		)
		(pad "AJ32" smd circle
			(at 15.500096 12.500102)
			(size 0.4572 0.4572)
			(layers "F.Cu" "F.Mask" "F.Paste")
			(net "PHY_SCC_TO_IOC_41_DP")
		)
		(pad "AK1" smd circle
			(at -15.500096 13.5001)
			(size 0.508 0.508)
			(layers "F.Cu" "F.Mask" "F.Paste")
			(net "GND")
		)
		(pad "AK2" smd circle
			(at -14.500098 13.5001)
			(size 0.508 0.508)
			(layers "F.Cu" "F.Mask" "F.Paste")
			(net "GB_VDDA")
		)
		(pad "AK3" smd circle
			(at -13.5001 13.5001)
			(size 0.508 0.508)
			(layers "F.Cu" "F.Mask" "F.Paste")
			(net "PHY_SCC_TO_DPB_13_DN")
		)
		(pad "AK4" smd circle
			(at -12.500102 13.5001)
			(size 0.4572 0.4572)
			(layers "F.Cu" "F.Mask" "F.Paste")
			(net "GB_VDDA")
		)
		(pad "AK5" smd circle
			(at -11.500104 13.5001)
			(size 0.4572 0.4572)
			(layers "F.Cu" "F.Mask" "F.Paste")
			(net "PHY_SCC_TO_DPB_15_DN")
		)
		(pad "AK6" smd circle
			(at -10.500106 13.5001)
			(size 0.4572 0.4572)
			(layers "F.Cu" "F.Mask" "F.Paste")
			(net "GB_VDDA")
		)
		(pad "AK7" smd circle
			(at -9.500108 13.5001)
			(size 0.4572 0.4572)
			(layers "F.Cu" "F.Mask" "F.Paste")
			(net "PHY_SCC_TO_DPB_17_DN")
		)
		(pad "AK8" smd circle
			(at -8.50011 13.5001)
			(size 0.4572 0.4572)
			(layers "F.Cu" "F.Mask" "F.Paste")
			(net "GB_VDDA")
		)
		(pad "AK9" smd circle
			(at -7.500112 13.5001)
			(size 0.4572 0.4572)
			(layers "F.Cu" "F.Mask" "F.Paste")
			(net "PHY_SCC_TO_DPB_19_DN")
		)
		(pad "AK10" smd circle
			(at -6.500114 13.5001)
			(size 0.4572 0.4572)
			(layers "F.Cu" "F.Mask" "F.Paste")
			(net "GB_VDDA")
		)
		(pad "AK11" smd circle
			(at -5.500116 13.5001)
			(size 0.4572 0.4572)
			(layers "F.Cu" "F.Mask" "F.Paste")
			(net "PHY_SCC_TO_DPB_21_DN")
		)
		(pad "AK12" smd circle
			(at -4.500118 13.5001)
			(size 0.4572 0.4572)
			(layers "F.Cu" "F.Mask" "F.Paste")
			(net "GB_VDDA")
		)
		(pad "AK13" smd circle
			(at -3.50012 13.5001)
			(size 0.4572 0.4572)
			(layers "F.Cu" "F.Mask" "F.Paste")
			(net "PHY_SCC_TO_DPB_23_DN")
		)
		(pad "AK14" smd circle
			(at -2.500122 13.5001)
			(size 0.4572 0.4572)
			(layers "F.Cu" "F.Mask" "F.Paste")
			(net "GB_VDDA")
		)
		(pad "AK15" smd circle
			(at -1.500124 13.5001)
			(size 0.4572 0.4572)
			(layers "F.Cu" "F.Mask" "F.Paste")
			(net "PHY_SCC_TO_DPB_25_DN")
		)
		(pad "AK16" smd circle
			(at -0.500126 13.5001)
			(size 0.4572 0.4572)
			(layers "F.Cu" "F.Mask" "F.Paste")
			(net "GB_VDDA")
		)
		(pad "AK17" smd circle
			(at 0.500126 13.5001)
			(size 0.4572 0.4572)
			(layers "F.Cu" "F.Mask" "F.Paste")
			(net "PHY_SCC_TO_DPB_27_DN")
		)
		(pad "AK18" smd circle
			(at 1.500124 13.5001)
			(size 0.4572 0.4572)
			(layers "F.Cu" "F.Mask" "F.Paste")
			(net "GB_VDDA")
		)
		(pad "AK19" smd circle
			(at 2.500122 13.5001)
			(size 0.4572 0.4572)
			(layers "F.Cu" "F.Mask" "F.Paste")
			(net "PHY_SCC_TO_DPB_33_DN")
		)
		(pad "AK20" smd circle
			(at 3.50012 13.5001)
			(size 0.4572 0.4572)
			(layers "F.Cu" "F.Mask" "F.Paste")
			(net "GB_VDDA")
		)
		(pad "AK21" smd circle
			(at 4.500118 13.5001)
			(size 0.4572 0.4572)
			(layers "F.Cu" "F.Mask" "F.Paste")
			(net "PHY_SCC_TO_DPB_35_DN")
		)
		(pad "AK22" smd circle
			(at 5.500116 13.5001)
			(size 0.4572 0.4572)
			(layers "F.Cu" "F.Mask" "F.Paste")
			(net "GB_VDDA")
		)
		(pad "AK23" smd circle
			(at 6.500114 13.5001)
			(size 0.4572 0.4572)
			(layers "F.Cu" "F.Mask" "F.Paste")
			(net "PHY_SCC_TO_DPB_37_DN")
		)
		(pad "AK24" smd circle
			(at 7.500112 13.5001)
			(size 0.4572 0.4572)
			(layers "F.Cu" "F.Mask" "F.Paste")
			(net "GB_VDDA")
		)
		(pad "AK25" smd circle
			(at 8.50011 13.5001)
			(size 0.4572 0.4572)
			(layers "F.Cu" "F.Mask" "F.Paste")
			(net "PHY_SCC_TO_DPB_39_DN")
		)
		(pad "AK26" smd circle
			(at 9.500108 13.5001)
			(size 0.4572 0.4572)
			(layers "F.Cu" "F.Mask" "F.Paste")
			(net "GND")
		)
		(pad "AK27" smd circle
			(at 10.500106 13.5001)
			(size 0.4572 0.4572)
			(layers "F.Cu" "F.Mask" "F.Paste")
			(net "GB_VDDA")
		)
		(pad "AK28" smd circle
			(at 11.500104 13.5001)
			(size 0.4572 0.4572)
			(layers "F.Cu" "F.Mask" "F.Paste")
			(net "PHY_IOC_TO_SCC_C_40_DN")
		)
		(pad "AK29" smd circle
			(at 12.500102 13.5001)
			(size 0.4572 0.4572)
			(layers "F.Cu" "F.Mask" "F.Paste")
			(net "PHY_IOC_TO_SCC_C_40_DP")
		)
		(pad "AK30" smd circle
			(at 13.5001 13.5001)
			(size 0.508 0.508)
			(layers "F.Cu" "F.Mask" "F.Paste")
			(net "GND")
		)
		(pad "AK31" smd circle
			(at 14.500098 13.5001)
			(size 0.508 0.508)
			(layers "F.Cu" "F.Mask" "F.Paste")
			(net "GND")
		)
	)
)
